(kicad_pcb
	(version 20260206)
	(generator "pcbnew")
	(generator_version "10.0")
	(general
		(thickness 1.6)
		(legacy_teardrops no)
	)
	(paper "A4")
	(title_block
		(title "03242023_DA0F0TMBIJ0_F0T_Motherboard_J_brd_V01_OCP.brd")
		(comment 1 "Grand Teton / footprints 2523-2529 of 6105")
	)
	(layers
		(0 "F.Cu" signal "TOP")
		(4 "In1.Cu" signal "GND")
		(6 "In2.Cu" signal "IN1")
		(8 "In3.Cu" signal "GND1")
		(10 "In4.Cu" signal "IN2")
		(12 "In5.Cu" signal "GND2")
		(14 "In6.Cu" signal "IN3")
		(16 "In7.Cu" signal "GND3")
		(18 "In8.Cu" signal "VCC")
		(20 "In9.Cu" signal "VCC1")
		(22 "In10.Cu" signal "GND4")
		(24 "In11.Cu" signal "IN4")
		(26 "In12.Cu" signal "GND5")
		(28 "In13.Cu" signal "IN5")
		(30 "In14.Cu" signal "GND6")
		(32 "In15.Cu" signal "IN6")
		(34 "In16.Cu" signal "GND7")
		(2 "B.Cu" signal "BOTTOM")
		(9 "F.Adhes" user "F.Adhesive")
		(11 "B.Adhes" user "B.Adhesive")
		(13 "F.Paste" user "Package Geometry/Pastemask Top")
		(15 "B.Paste" user "Package Geometry/Pastemask Bottom")
		(5 "F.SilkS" user "Ref Des/Silkscreen Top")
		(7 "B.SilkS" user "Ref Des/Silkscreen Bottom")
		(1 "F.Mask" user "Board Geometry/Soldermask Top")
		(3 "B.Mask" user "Board Geometry/Soldermask Bottom")
		(17 "Dwgs.User" user "User.Drawings")
		(19 "Cmts.User" user "User.Comments")
		(21 "Eco1.User" user "User.Eco1")
		(23 "Eco2.User" user "User.Eco2")
		(25 "Edge.Cuts" user "Board Geometry/Outline")
		(27 "Margin" user)
		(31 "F.CrtYd" user "Package Geometry/Place Bound Top")
		(29 "B.CrtYd" user "Package Geometry/Place Bound Bottom")
		(35 "F.Fab" user "Ref Des/Assembly Top")
		(33 "B.Fab" user "Ref Des/Assembly Bottom")
	)
	(footprint ""
		(layer "F.Cu")
		(at 40.413178 -397.406622 90)
		(property "Reference" "R4654"
			(at 0 0 90)
			(layer "F.SilkS")
			(hide yes)
			(effects
				(font
					(size 1.27 1.27)
				)
			)
		)
		(property "Value" ""
			(at 0 0 90)
			(layer "F.Fab")
			(effects
				(font
					(size 1.27 1.27)
				)
			)
		)
		(duplicate_pad_numbers_are_jumpers no)
		(fp_line
			(start 0.7874 -0.4064)
			(end 0.7874 0.4064)
			(stroke
				(width 0.1524)
				(type default)
			)
			(layer "F.SilkS")
		)
		(fp_line
			(start -0.7874 -0.4064)
			(end 0.7874 -0.4064)
			(stroke
				(width 0.1524)
				(type default)
			)
			(layer "F.SilkS")
		)
		(fp_line
			(start 0.7874 0.4064)
			(end -0.7874 0.4064)
			(stroke
				(width 0.1524)
				(type default)
			)
			(layer "F.SilkS")
		)
		(fp_line
			(start -0.7874 0.4064)
			(end -0.7874 -0.4064)
			(stroke
				(width 0.1524)
				(type default)
			)
			(layer "F.SilkS")
		)
		(fp_line
			(start -0.12065 -0.305054)
			(end -0.12065 -0.2794)
			(stroke
				(width 0.1)
				(type default)
			)
			(layer "F.Fab")
		)
		(fp_line
			(start -0.67945 -0.305054)
			(end -0.12065 -0.305054)
			(stroke
				(width 0.1)
				(type default)
			)
			(layer "F.Fab")
		)
		(fp_line
			(start 0.67945 -0.3048)
			(end 0.67945 0.3048)
			(stroke
				(width 0.1)
				(type default)
			)
			(layer "F.Fab")
		)
		(fp_line
			(start 0.12065 -0.3048)
			(end 0.67945 -0.3048)
			(stroke
				(width 0.1)
				(type default)
			)
			(layer "F.Fab")
		)
		(fp_line
			(start 0.12065 -0.2794)
			(end 0.12065 -0.3048)
			(stroke
				(width 0.1)
				(type default)
			)
			(layer "F.Fab")
		)
		(fp_line
			(start -0.12065 -0.2794)
			(end 0.12065 -0.2794)
			(stroke
				(width 0.1)
				(type default)
			)
			(layer "F.Fab")
		)
		(fp_line
			(start 0.120396 0.2794)
			(end -0.12065 0.2794)
			(stroke
				(width 0.1)
				(type default)
			)
			(layer "F.Fab")
		)
		(fp_line
			(start -0.12065 0.2794)
			(end -0.12065 0.3048)
			(stroke
				(width 0.1)
				(type default)
			)
			(layer "F.Fab")
		)
		(fp_line
			(start 0.67945 0.3048)
			(end 0.120396 0.3048)
			(stroke
				(width 0.1)
				(type default)
			)
			(layer "F.Fab")
		)
		(fp_line
			(start 0.120396 0.3048)
			(end 0.120396 0.2794)
			(stroke
				(width 0.1)
				(type default)
			)
			(layer "F.Fab")
		)
		(fp_line
			(start -0.12065 0.3048)
			(end -0.67945 0.3048)
			(stroke
				(width 0.1)
				(type default)
			)
			(layer "F.Fab")
		)
		(fp_line
			(start -0.67945 0.3048)
			(end -0.67945 -0.305054)
			(stroke
				(width 0.1)
				(type default)
			)
			(layer "F.Fab")
		)
		(pad "1" smd circle
			(at -0.40005 0 90)
			(size 0 0)
			(layers "F.Cu" "F.Mask" "F.Paste")
			(net "FM_P2E_BUF2_EQA1")
		)
		(pad "2" smd circle
			(at 0.40005 0 90)
			(size 0 0)
			(layers "F.Cu" "F.Mask" "F.Paste")
			(net "GND")
		)
	)
	(footprint ""
		(layer "F.Cu")
		(at 208.054956 -30.276292 90)
		(property "Reference" "R3612"
			(at 0 0 90)
			(layer "F.SilkS")
			(hide yes)
			(effects
				(font
					(size 1.27 1.27)
				)
			)
		)
		(property "Value" ""
			(at 0 0 90)
			(layer "F.Fab")
			(effects
				(font
					(size 1.27 1.27)
				)
			)
		)
		(duplicate_pad_numbers_are_jumpers no)
		(fp_line
			(start 0.7874 -0.4064)
			(end 0.7874 0.4064)
			(stroke
				(width 0.1524)
				(type default)
			)
			(layer "F.SilkS")
		)
		(fp_line
			(start -0.7874 -0.4064)
			(end 0.7874 -0.4064)
			(stroke
				(width 0.1524)
				(type default)
			)
			(layer "F.SilkS")
		)
		(fp_line
			(start 0.7874 0.4064)
			(end -0.7874 0.4064)
			(stroke
				(width 0.1524)
				(type default)
			)
			(layer "F.SilkS")
		)
		(fp_line
			(start -0.7874 0.4064)
			(end -0.7874 -0.4064)
			(stroke
				(width 0.1524)
				(type default)
			)
			(layer "F.SilkS")
		)
		(fp_line
			(start -0.12065 -0.305054)
			(end -0.12065 -0.2794)
			(stroke
				(width 0.1)
				(type default)
			)
			(layer "F.Fab")
		)
		(fp_line
			(start -0.67945 -0.305054)
			(end -0.12065 -0.305054)
			(stroke
				(width 0.1)
				(type default)
			)
			(layer "F.Fab")
		)
		(fp_line
			(start 0.67945 -0.3048)
			(end 0.67945 0.3048)
			(stroke
				(width 0.1)
				(type default)
			)
			(layer "F.Fab")
		)
		(fp_line
			(start 0.12065 -0.3048)
			(end 0.67945 -0.3048)
			(stroke
				(width 0.1)
				(type default)
			)
			(layer "F.Fab")
		)
		(fp_line
			(start 0.12065 -0.2794)
			(end 0.12065 -0.3048)
			(stroke
				(width 0.1)
				(type default)
			)
			(layer "F.Fab")
		)
		(fp_line
			(start -0.12065 -0.2794)
			(end 0.12065 -0.2794)
			(stroke
				(width 0.1)
				(type default)
			)
			(layer "F.Fab")
		)
		(fp_line
			(start 0.120396 0.2794)
			(end -0.12065 0.2794)
			(stroke
				(width 0.1)
				(type default)
			)
			(layer "F.Fab")
		)
		(fp_line
			(start -0.12065 0.2794)
			(end -0.12065 0.3048)
			(stroke
				(width 0.1)
				(type default)
			)
			(layer "F.Fab")
		)
		(fp_line
			(start 0.67945 0.3048)
			(end 0.120396 0.3048)
			(stroke
				(width 0.1)
				(type default)
			)
			(layer "F.Fab")
		)
		(fp_line
			(start 0.120396 0.3048)
			(end 0.120396 0.2794)
			(stroke
				(width 0.1)
				(type default)
			)
			(layer "F.Fab")
		)
		(fp_line
			(start -0.12065 0.3048)
			(end -0.67945 0.3048)
			(stroke
				(width 0.1)
				(type default)
			)
			(layer "F.Fab")
		)
		(fp_line
			(start -0.67945 0.3048)
			(end -0.67945 -0.305054)
			(stroke
				(width 0.1)
				(type default)
			)
			(layer "F.Fab")
		)
		(pad "1" smd circle
			(at -0.40005 0 90)
			(size 0 0)
			(layers "F.Cu" "F.Mask" "F.Paste")
			(net "GND")
		)
		(pad "2" smd circle
			(at 0.40005 0 90)
			(size 0 0)
			(layers "F.Cu" "F.Mask" "F.Paste")
			(net "INA230_5_A1")
		)
	)
	(footprint ""
		(layer "F.Cu")
		(at 412.13405 -402.371052 -90)
		(property "Reference" "C960"
			(at 0 0 270)
			(layer "F.SilkS")
			(hide yes)
			(effects
				(font
					(size 1.27 1.27)
				)
			)
		)
		(property "Value" ""
			(at 0 0 270)
			(layer "F.Fab")
			(effects
				(font
					(size 1.27 1.27)
				)
			)
		)
		(duplicate_pad_numbers_are_jumpers no)
		(fp_line
			(start -0.299974 0.150114)
			(end -0.299974 -0.150114)
			(stroke
				(width 0.1)
				(type default)
			)
			(layer "F.Fab")
		)
		(fp_line
			(start 0.299974 0.150114)
			(end -0.299974 0.150114)
			(stroke
				(width 0.1)
				(type default)
			)
			(layer "F.Fab")
		)
		(fp_line
			(start -0.299974 -0.150114)
			(end 0.299974 -0.150114)
			(stroke
				(width 0.1)
				(type default)
			)
			(layer "F.Fab")
		)
		(fp_line
			(start 0.299974 -0.150114)
			(end 0.299974 0.150114)
			(stroke
				(width 0.1)
				(type default)
			)
			(layer "F.Fab")
		)
		(pad "1" smd rect
			(at -0.2667 0 270)
			(size 0.3048 0.381)
			(layers "F.Cu" "F.Mask" "F.Paste")
			(net "P5E_CPU0_PE2_TX_C_DN<2>")
		)
		(pad "2" smd rect
			(at 0.2667 0 270)
			(size 0.3048 0.381)
			(layers "F.Cu" "F.Mask" "F.Paste")
			(net "P5E_CPU0_PE2_TX_DN<2>")
		)
	)
	(footprint ""
		(layer "F.Cu")
		(at 422.74744 -152.024588)
		(property "Reference" "PR1778"
			(at 0 0 0)
			(layer "F.SilkS")
			(hide yes)
			(effects
				(font
					(size 1.27 1.27)
				)
			)
		)
		(property "Value" ""
			(at 0 0 0)
			(layer "F.Fab")
			(effects
				(font
					(size 1.27 1.27)
				)
			)
		)
		(duplicate_pad_numbers_are_jumpers no)
		(fp_line
			(start -0.7874 -0.4064)
			(end 0.7874 -0.4064)
			(stroke
				(width 0.1524)
				(type default)
			)
			(layer "F.SilkS")
		)
		(fp_line
			(start -0.7874 0.4064)
			(end -0.7874 -0.4064)
			(stroke
				(width 0.1524)
				(type default)
			)
			(layer "F.SilkS")
		)
		(fp_line
			(start 0.7874 -0.4064)
			(end 0.7874 0.4064)
			(stroke
				(width 0.1524)
				(type default)
			)
			(layer "F.SilkS")
		)
		(fp_line
			(start 0.7874 0.4064)
			(end -0.7874 0.4064)
			(stroke
				(width 0.1524)
				(type default)
			)
			(layer "F.SilkS")
		)
		(fp_line
			(start -0.67945 -0.305054)
			(end -0.12065 -0.305054)
			(stroke
				(width 0.1)
				(type default)
			)
			(layer "F.Fab")
		)
		(fp_line
			(start -0.67945 0.3048)
			(end -0.67945 -0.305054)
			(stroke
				(width 0.1)
				(type default)
			)
			(layer "F.Fab")
		)
		(fp_line
			(start -0.12065 -0.305054)
			(end -0.12065 -0.2794)
			(stroke
				(width 0.1)
				(type default)
			)
			(layer "F.Fab")
		)
		(fp_line
			(start -0.12065 -0.2794)
			(end 0.12065 -0.2794)
			(stroke
				(width 0.1)
				(type default)
			)
			(layer "F.Fab")
		)
		(fp_line
			(start -0.12065 0.2794)
			(end -0.12065 0.3048)
			(stroke
				(width 0.1)
				(type default)
			)
			(layer "F.Fab")
		)
		(fp_line
			(start -0.12065 0.3048)
			(end -0.67945 0.3048)
			(stroke
				(width 0.1)
				(type default)
			)
			(layer "F.Fab")
		)
		(fp_line
			(start 0.120396 0.2794)
			(end -0.12065 0.2794)
			(stroke
				(width 0.1)
				(type default)
			)
			(layer "F.Fab")
		)
		(fp_line
			(start 0.120396 0.3048)
			(end 0.120396 0.2794)
			(stroke
				(width 0.1)
				(type default)
			)
			(layer "F.Fab")
		)
		(fp_line
			(start 0.12065 -0.3048)
			(end 0.67945 -0.3048)
			(stroke
				(width 0.1)
				(type default)
			)
			(layer "F.Fab")
		)
		(fp_line
			(start 0.12065 -0.2794)
			(end 0.12065 -0.3048)
			(stroke
				(width 0.1)
				(type default)
			)
			(layer "F.Fab")
		)
		(fp_line
			(start 0.67945 -0.3048)
			(end 0.67945 0.3048)
			(stroke
				(width 0.1)
				(type default)
			)
			(layer "F.Fab")
		)
		(fp_line
			(start 0.67945 0.3048)
			(end 0.120396 0.3048)
			(stroke
				(width 0.1)
				(type default)
			)
			(layer "F.Fab")
		)
		(pad "1" smd circle
			(at -0.40005 0)
			(size 0 0)
			(layers "F.Cu" "F.Mask" "F.Paste")
			(net "SW_PVCCFA_EHV_CPU0_BOOT1")
		)
		(pad "2" smd circle
			(at 0.40005 0)
			(size 0 0)
			(layers "F.Cu" "F.Mask" "F.Paste")
			(net "SW_PVCCFA_EHV_CPU0_BOOT1_R")
		)
	)
	(footprint ""
		(layer "F.Cu")
		(at 11.421618 -105.48239 90)
		(property "Reference" "R2786"
			(at 0 0 90)
			(layer "F.SilkS")
			(hide yes)
			(effects
				(font
					(size 1.27 1.27)
				)
			)
		)
		(property "Value" ""
			(at 0 0 90)
			(layer "F.Fab")
			(effects
				(font
					(size 1.27 1.27)
				)
			)
		)
		(duplicate_pad_numbers_are_jumpers no)
		(fp_line
			(start 0.7874 -0.4064)
			(end 0.7874 0.4064)
			(stroke
				(width 0.1524)
				(type default)
			)
			(layer "F.SilkS")
		)
		(fp_line
			(start -0.7874 -0.4064)
			(end 0.7874 -0.4064)
			(stroke
				(width 0.1524)
				(type default)
			)
			(layer "F.SilkS")
		)
		(fp_line
			(start 0.01651 0.4064)
			(end -0.7874 0.4064)
			(stroke
				(width 0.1524)
				(type default)
			)
			(layer "F.SilkS")
		)
		(fp_line
			(start -0.12065 -0.305054)
			(end -0.12065 -0.2794)
			(stroke
				(width 0.1)
				(type default)
			)
			(layer "F.Fab")
		)
		(fp_line
			(start -0.67945 -0.305054)
			(end -0.12065 -0.305054)
			(stroke
				(width 0.1)
				(type default)
			)
			(layer "F.Fab")
		)
		(fp_line
			(start 0.67945 -0.3048)
			(end 0.67945 0.3048)
			(stroke
				(width 0.1)
				(type default)
			)
			(layer "F.Fab")
		)
		(fp_line
			(start 0.12065 -0.3048)
			(end 0.67945 -0.3048)
			(stroke
				(width 0.1)
				(type default)
			)
			(layer "F.Fab")
		)
		(fp_line
			(start 0.12065 -0.2794)
			(end 0.12065 -0.3048)
			(stroke
				(width 0.1)
				(type default)
			)
			(layer "F.Fab")
		)
		(fp_line
			(start -0.12065 -0.2794)
			(end 0.12065 -0.2794)
			(stroke
				(width 0.1)
				(type default)
			)
			(layer "F.Fab")
		)
		(fp_line
			(start 0.120396 0.2794)
			(end -0.12065 0.2794)
			(stroke
				(width 0.1)
				(type default)
			)
			(layer "F.Fab")
		)
		(fp_line
			(start -0.12065 0.2794)
			(end -0.12065 0.3048)
			(stroke
				(width 0.1)
				(type default)
			)
			(layer "F.Fab")
		)
		(fp_line
			(start 0.67945 0.3048)
			(end 0.120396 0.3048)
			(stroke
				(width 0.1)
				(type default)
			)
			(layer "F.Fab")
		)
		(fp_line
			(start 0.120396 0.3048)
			(end 0.120396 0.2794)
			(stroke
				(width 0.1)
				(type default)
			)
			(layer "F.Fab")
		)
		(fp_line
			(start -0.12065 0.3048)
			(end -0.67945 0.3048)
			(stroke
				(width 0.1)
				(type default)
			)
			(layer "F.Fab")
		)
		(fp_line
			(start -0.67945 0.3048)
			(end -0.67945 -0.305054)
			(stroke
				(width 0.1)
				(type default)
			)
			(layer "F.Fab")
		)
		(pad "1" smd rect
			(at -0.40005 0 270)
			(size 0.4572 0.508)
			(layers "F.Cu" "F.Mask" "F.Paste")
			(net "USB2_HUB_SWB_DP")
		)
		(pad "2" smd rect
			(at 0.40005 0 270)
			(size 0.4572 0.508)
			(layers "F.Cu" "F.Mask" "F.Paste")
			(net "USB2_HUB_BUF_SWB_R_DP")
		)
	)
	(footprint ""
		(layer "F.Cu")
		(at 345.98483 -338.180172 90)
		(property "Reference" "PR1787"
			(at 0 0 90)
			(layer "F.SilkS")
			(hide yes)
			(effects
				(font
					(size 1.27 1.27)
				)
			)
		)
		(property "Value" ""
			(at 0 0 90)
			(layer "F.Fab")
			(effects
				(font
					(size 1.27 1.27)
				)
			)
		)
		(duplicate_pad_numbers_are_jumpers no)
		(fp_line
			(start 0.7874 -0.4064)
			(end 0.7874 0.4064)
			(stroke
				(width 0.1524)
				(type default)
			)
			(layer "F.SilkS")
		)
		(fp_line
			(start -0.7874 -0.4064)
			(end 0.7874 -0.4064)
			(stroke
				(width 0.1524)
				(type default)
			)
			(layer "F.SilkS")
		)
		(fp_line
			(start 0.7874 0.4064)
			(end -0.7874 0.4064)
			(stroke
				(width 0.1524)
				(type default)
			)
			(layer "F.SilkS")
		)
		(fp_line
			(start -0.7874 0.4064)
			(end -0.7874 -0.4064)
			(stroke
				(width 0.1524)
				(type default)
			)
			(layer "F.SilkS")
		)
		(fp_line
			(start -0.12065 -0.305054)
			(end -0.12065 -0.2794)
			(stroke
				(width 0.1)
				(type default)
			)
			(layer "F.Fab")
		)
		(fp_line
			(start -0.67945 -0.305054)
			(end -0.12065 -0.305054)
			(stroke
				(width 0.1)
				(type default)
			)
			(layer "F.Fab")
		)
		(fp_line
			(start 0.67945 -0.3048)
			(end 0.67945 0.3048)
			(stroke
				(width 0.1)
				(type default)
			)
			(layer "F.Fab")
		)
		(fp_line
			(start 0.12065 -0.3048)
			(end 0.67945 -0.3048)
			(stroke
				(width 0.1)
				(type default)
			)
			(layer "F.Fab")
		)
		(fp_line
			(start 0.12065 -0.2794)
			(end 0.12065 -0.3048)
			(stroke
				(width 0.1)
				(type default)
			)
			(layer "F.Fab")
		)
		(fp_line
			(start -0.12065 -0.2794)
			(end 0.12065 -0.2794)
			(stroke
				(width 0.1)
				(type default)
			)
			(layer "F.Fab")
		)
		(fp_line
			(start 0.120396 0.2794)
			(end -0.12065 0.2794)
			(stroke
				(width 0.1)
				(type default)
			)
			(layer "F.Fab")
		)
		(fp_line
			(start -0.12065 0.2794)
			(end -0.12065 0.3048)
			(stroke
				(width 0.1)
				(type default)
			)
			(layer "F.Fab")
		)
		(fp_line
			(start 0.67945 0.3048)
			(end 0.120396 0.3048)
			(stroke
				(width 0.1)
				(type default)
			)
			(layer "F.Fab")
		)
		(fp_line
			(start 0.120396 0.3048)
			(end 0.120396 0.2794)
			(stroke
				(width 0.1)
				(type default)
			)
			(layer "F.Fab")
		)
		(fp_line
			(start -0.12065 0.3048)
			(end -0.67945 0.3048)
			(stroke
				(width 0.1)
				(type default)
			)
			(layer "F.Fab")
		)
		(fp_line
			(start -0.67945 0.3048)
			(end -0.67945 -0.305054)
			(stroke
				(width 0.1)
				(type default)
			)
			(layer "F.Fab")
		)
		(pad "1" smd circle
			(at -0.40005 0 90)
			(size 0 0)
			(layers "F.Cu" "F.Mask" "F.Paste")
			(net "SW_PVCCIN_CPU0_BOOT1")
		)
		(pad "2" smd circle
			(at 0.40005 0 90)
			(size 0 0)
			(layers "F.Cu" "F.Mask" "F.Paste")
			(net "SW_PVCCIN_CPU0_BOOT1_R")
		)
	)
	(footprint ""
		(layer "F.Cu")
		(at 381.756666 -340.064598)
		(property "Reference" "PC253_P0_5"
			(at 0 0 0)
			(layer "F.SilkS")
			(hide yes)
			(effects
				(font
					(size 1.27 1.27)
				)
			)
		)
		(property "Value" ""
			(at 0 0 0)
			(layer "F.Fab")
			(effects
				(font
					(size 1.27 1.27)
				)
			)
		)
		(duplicate_pad_numbers_are_jumpers no)
		(fp_line
			(start -0.7874 -0.4064)
			(end 0.7874 -0.4064)
			(stroke
				(width 0.1524)
				(type default)
			)
			(layer "F.SilkS")
		)
		(fp_line
			(start -0.7874 0.4064)
			(end -0.7874 -0.4064)
			(stroke
				(width 0.1524)
				(type default)
			)
			(layer "F.SilkS")
		)
		(fp_line
			(start 0.7874 -0.4064)
			(end 0.7874 0.4064)
			(stroke
				(width 0.1524)
				(type default)
			)
			(layer "F.SilkS")
		)
		(fp_line
			(start 0.7874 0.4064)
			(end -0.7874 0.4064)
			(stroke
				(width 0.1524)
				(type default)
			)
			(layer "F.SilkS")
		)
		(fp_line
			(start -0.67945 -0.305054)
			(end -0.12065 -0.305054)
			(stroke
				(width 0.1)
				(type default)
			)
			(layer "F.Fab")
		)
		(fp_line
			(start -0.67945 0.3048)
			(end -0.67945 -0.305054)
			(stroke
				(width 0.1)
				(type default)
			)
			(layer "F.Fab")
		)
		(fp_line
			(start -0.12065 -0.305054)
			(end -0.12065 -0.2794)
			(stroke
				(width 0.1)
				(type default)
			)
			(layer "F.Fab")
		)
		(fp_line
			(start -0.12065 -0.2794)
			(end 0.12065 -0.2794)
			(stroke
				(width 0.1)
				(type default)
			)
			(layer "F.Fab")
		)
		(fp_line
			(start -0.12065 0.2794)
			(end -0.12065 0.3048)
			(stroke
				(width 0.1)
				(type default)
			)
			(layer "F.Fab")
		)
		(fp_line
			(start -0.12065 0.3048)
			(end -0.67945 0.3048)
			(stroke
				(width 0.1)
				(type default)
			)
			(layer "F.Fab")
		)
		(fp_line
			(start 0.120396 0.2794)
			(end -0.12065 0.2794)
			(stroke
				(width 0.1)
				(type default)
			)
			(layer "F.Fab")
		)
		(fp_line
			(start 0.120396 0.3048)
			(end 0.120396 0.2794)
			(stroke
				(width 0.1)
				(type default)
			)
			(layer "F.Fab")
		)
		(fp_line
			(start 0.12065 -0.3048)
			(end 0.67945 -0.3048)
			(stroke
				(width 0.1)
				(type default)
			)
			(layer "F.Fab")
		)
		(fp_line
			(start 0.12065 -0.2794)
			(end 0.12065 -0.3048)
			(stroke
				(width 0.1)
				(type default)
			)
			(layer "F.Fab")
		)
		(fp_line
			(start 0.67945 -0.3048)
			(end 0.67945 0.3048)
			(stroke
				(width 0.1)
				(type default)
			)
			(layer "F.Fab")
		)
		(fp_line
			(start 0.67945 0.3048)
			(end 0.120396 0.3048)
			(stroke
				(width 0.1)
				(type default)
			)
			(layer "F.Fab")
		)
		(pad "1" smd circle
			(at -0.40005 0)
			(size 0 0)
			(layers "F.Cu" "F.Mask" "F.Paste")
			(net "SW_P12V_PVCCIN_CPU0_FLT")
		)
		(pad "2" smd circle
			(at 0.40005 0)
			(size 0 0)
			(layers "F.Cu" "F.Mask" "F.Paste")
			(net "GND")
		)
	)
)
